(kicad_pcb
	(version 20260206)
	(generator "pcbnew")
	(generator_version "10.0")
	(general
		(thickness 1.6)
		(legacy_teardrops no)
	)
	(paper "A4")
	(title_block
		(title "Wiwynn_Tioga_Pass_MB.brd")
		(comment 1 "Tioga Pass / footprints 131-137 of 4770")
	)
	(layers
		(0 "F.Cu" signal "TOP")
		(4 "In1.Cu" signal "L2GND")
		(6 "In2.Cu" signal "L3")
		(8 "In3.Cu" signal "L4GND")
		(10 "In4.Cu" signal "L5")
		(12 "In5.Cu" signal "L6GND")
		(14 "In6.Cu" signal "L7VCC")
		(16 "In7.Cu" signal "L8VCC")
		(18 "In8.Cu" signal "L9GND")
		(20 "In9.Cu" signal "L10")
		(22 "In10.Cu" signal "L11GND")
		(24 "In11.Cu" signal "L12")
		(26 "In12.Cu" signal "L13GND")
		(2 "B.Cu" signal "BOTTOM")
		(9 "F.Adhes" user "F.Adhesive")
		(11 "B.Adhes" user "B.Adhesive")
		(13 "F.Paste" user "Package Geometry/Pastemask Top")
		(15 "B.Paste" user "Package Geometry/Pastemask Bottom")
		(5 "F.SilkS" user "Ref Des/Silkscreen Top")
		(7 "B.SilkS" user "Ref Des/Silkscreen Bottom")
		(1 "F.Mask" user "Board Geometry/Soldermask Top")
		(3 "B.Mask" user "Board Geometry/Soldermask Bottom")
		(17 "Dwgs.User" user "User.Drawings")
		(19 "Cmts.User" user "User.Comments")
		(21 "Eco1.User" user "User.Eco1")
		(23 "Eco2.User" user "User.Eco2")
		(25 "Edge.Cuts" user "Board Geometry/Outline")
		(27 "Margin" user)
		(31 "F.CrtYd" user "Package Geometry/Place Bound Top")
		(29 "B.CrtYd" user "Package Geometry/Place Bound Bottom")
		(35 "F.Fab" user "Ref Des/Assembly Top")
		(33 "B.Fab" user "Ref Des/Assembly Bottom")
	)
	(footprint ""
		(layer "F.Cu")
		(at 492.4806 -59.944 180)
		(property "Reference" "C30W3"
			(at 0 0 180)
			(layer "F.SilkS")
			(hide yes)
			(effects
				(font
					(size 1.27 1.27)
				)
			)
		)
		(property "Value" "*"
			(at -0.0762 -6.2357 180)
			(unlocked yes)
			(layer "F.Fab")
			(hide yes)
			(effects
				(font
					(size 1.27 1.016)
					(thickness 0.1524)
				)
			)
		)
		(property "Device Type" "SC22U16V5MX-4-GP_SMD-BCG5-SC22A"
			(at -0.0762 -8.2677 180)
			(unlocked yes)
			(layer "F.Fab")
			(hide yes)
			(effects
				(font
					(size 1.27 1.016)
					(thickness 0.1524)
				)
			)
		)
		(duplicate_pad_numbers_are_jumpers no)
		(fp_line
			(start 0.635 0)
			(end -0.635 0)
			(stroke
				(width 0.508)
				(type default)
			)
			(layer "F.SilkS")
		)
		(fp_rect
			(start -0.9652 1.778)
			(end 0.9652 -1.778)
			(stroke
				(width 0)
				(type default)
			)
			(fill no)
			(layer "F.CrtYd")
		)
		(fp_poly
			(pts
				(xy -0.9652 -1.778) (xy 0.9652 -1.778) (xy 0.9652 1.778) (xy -0.9652 1.778)
			)
			(stroke
				(width 0)
				(type default)
			)
			(fill no)
			(layer "F.Fab")
		)
		(pad "1" smd rect
			(at 0 -0.9652 180)
			(size 1.397 1.143)
			(layers "F.Cu" "F.Mask" "F.Paste")
			(net "P5V_STBY_USBC")
		)
		(pad "2" smd rect
			(at 0 0.9652 180)
			(size 1.397 1.143)
			(layers "F.Cu" "F.Mask" "F.Paste")
			(net "GND")
		)
	)
	(footprint ""
		(layer "F.Cu")
		(at -2.667 -129.3622 -90)
		(property "Reference" "R12W35"
			(at -0.8382 -0.67818 270)
			(unlocked yes)
			(layer "F.SilkS")
			(effects
				(font
					(size 0.4064 0.254)
					(thickness 0.1524)
				)
				(justify left)
			)
		)
		(property "Value" ""
			(at 0 0 270)
			(layer "F.Fab")
			(effects
				(font
					(size 1.27 1.27)
				)
			)
		)
		(duplicate_pad_numbers_are_jumpers no)
		(fp_poly
			(pts
				(xy -0.2794 -0.1016) (xy 0.2794 -0.1016) (xy 0.2794 0.9906) (xy -0.2794 0.9906)
			)
			(stroke
				(width 0)
				(type default)
			)
			(fill no)
			(layer "F.CrtYd")
		)
		(fp_line
			(start -0.2794 0.9906)
			(end 0.2794 0.9906)
			(stroke
				(width 0.1)
				(type default)
			)
			(layer "F.Fab")
		)
		(fp_line
			(start 0.2794 0.9906)
			(end 0.2794 -0.1016)
			(stroke
				(width 0.1)
				(type default)
			)
			(layer "F.Fab")
		)
		(fp_line
			(start -0.2794 -0.1016)
			(end -0.2794 0.9906)
			(stroke
				(width 0.1)
				(type default)
			)
			(layer "F.Fab")
		)
		(fp_line
			(start 0.2794 -0.1016)
			(end -0.2794 -0.1016)
			(stroke
				(width 0.1)
				(type default)
			)
			(layer "F.Fab")
		)
		(pad "1" smd rect
			(at 0 0 270)
			(size 0.508 0.508)
			(layers "F.Cu" "F.Mask" "F.Paste")
			(net "NC_PVDDQ_KLM_GP1")
		)
		(pad "2" smd rect
			(at 0 0.889 270)
			(size 0.508 0.508)
			(layers "F.Cu" "F.Mask" "F.Paste")
			(net "PWRGD_PVDDQ_KLM")
		)
		(zone
			(layer "F.Cu")
			(hatch none 0.5)
			(connect_pads
				(clearance 0)
			)
			(min_thickness 0.25)
			(keepout
				(tracks not_allowed)
				(vias allowed)
				(pads allowed)
				(copperpour not_allowed)
				(footprints allowed)
			)
			(placement
				(enabled no)
				(sheetname "")
			)
			(fill
				(thermal_gap 0.5)
				(thermal_bridge_width 0.5)
				(island_removal_mode 0)
			)
			(polygon
				(pts
					(xy -3.302 -129.6162) (xy -3.302 -129.1082) (xy -2.921 -129.1082) (xy -2.921 -129.6162)
				)
			)
		)
		(zone
			(layer "F.Cu")
			(hatch none 0.5)
			(connect_pads
				(clearance 0)
			)
			(min_thickness 0.25)
			(keepout
				(tracks allowed)
				(vias not_allowed)
				(pads allowed)
				(copperpour not_allowed)
				(footprints allowed)
			)
			(placement
				(enabled no)
				(sheetname "")
			)
			(fill
				(thermal_gap 0.5)
				(thermal_bridge_width 0.5)
				(island_removal_mode 0)
			)
			(polygon
				(pts
					(xy -2.921 -129.6162) (xy -2.921 -129.1082) (xy -3.302 -129.1082) (xy -3.302 -129.6162)
				)
			)
		)
	)
	(footprint ""
		(layer "F.Cu")
		(at -2.789682 -140.048996 90)
		(property "Reference" "C1A18"
			(at 0 0 90)
			(layer "F.SilkS")
			(hide yes)
			(effects
				(font
					(size 1.27 1.27)
				)
			)
		)
		(property "Value" ""
			(at 0 0 90)
			(layer "F.Fab")
			(effects
				(font
					(size 1.27 1.27)
				)
			)
		)
		(duplicate_pad_numbers_are_jumpers no)
		(fp_poly
			(pts
				(xy 0.3048 -0.1016) (xy 0.3048 0.9906) (xy -0.3048 0.9906) (xy -0.3048 -0.1016)
			)
			(stroke
				(width 0)
				(type default)
			)
			(fill no)
			(layer "F.CrtYd")
		)
		(fp_line
			(start 0.3048 -0.1016)
			(end -0.3048 -0.1016)
			(stroke
				(width 0.1)
				(type default)
			)
			(layer "F.Fab")
		)
		(fp_line
			(start -0.3048 -0.1016)
			(end -0.3048 0.9906)
			(stroke
				(width 0.1)
				(type default)
			)
			(layer "F.Fab")
		)
		(fp_line
			(start 0.3048 0.9906)
			(end 0.3048 -0.1016)
			(stroke
				(width 0.1)
				(type default)
			)
			(layer "F.Fab")
		)
		(fp_line
			(start -0.3048 0.9906)
			(end 0.3048 0.9906)
			(stroke
				(width 0.1)
				(type default)
			)
			(layer "F.Fab")
		)
		(pad "1" smd rect
			(at 0 0 90)
			(size 0.508 0.508)
			(layers "F.Cu" "F.Mask" "F.Paste")
			(net "VR_PVDDQ_KLM_PH1_BOOT")
		)
		(pad "2" smd rect
			(at 0 0.889 90)
			(size 0.508 0.508)
			(layers "F.Cu" "F.Mask" "F.Paste")
			(net "VR_PVDDQ_KLM_PH1_PHASE")
		)
		(zone
			(layer "F.Cu")
			(hatch none 0.5)
			(connect_pads
				(clearance 0)
			)
			(min_thickness 0.25)
			(keepout
				(tracks allowed)
				(vias not_allowed)
				(pads allowed)
				(copperpour not_allowed)
				(footprints allowed)
			)
			(placement
				(enabled no)
				(sheetname "")
			)
			(fill
				(thermal_gap 0.5)
				(thermal_bridge_width 0.5)
				(island_removal_mode 0)
			)
			(polygon
				(pts
					(xy -2.535682 -139.794996) (xy -2.535682 -140.302996) (xy -2.154682 -140.302996) (xy -2.154682 -139.794996)
				)
			)
		)
		(zone
			(layer "F.Cu")
			(hatch none 0.5)
			(connect_pads
				(clearance 0)
			)
			(min_thickness 0.25)
			(keepout
				(tracks not_allowed)
				(vias allowed)
				(pads allowed)
				(copperpour not_allowed)
				(footprints allowed)
			)
			(placement
				(enabled no)
				(sheetname "")
			)
			(fill
				(thermal_gap 0.5)
				(thermal_bridge_width 0.5)
				(island_removal_mode 0)
			)
			(polygon
				(pts
					(xy -2.154682 -139.794996) (xy -2.154682 -140.302996) (xy -2.535682 -140.302996) (xy -2.535682 -139.794996)
				)
			)
		)
	)
	(footprint ""
		(layer "F.Cu")
		(at 176.0855 -8.763 90)
		(property "Reference" "C4G6"
			(at 0 0 90)
			(layer "F.SilkS")
			(hide yes)
			(effects
				(font
					(size 1.27 1.27)
				)
			)
		)
		(property "Value" ""
			(at 0 0 90)
			(layer "F.Fab")
			(effects
				(font
					(size 1.27 1.27)
				)
			)
		)
		(duplicate_pad_numbers_are_jumpers no)
		(fp_poly
			(pts
				(xy 0.3048 -0.1016) (xy 0.3048 0.9906) (xy -0.3048 0.9906) (xy -0.3048 -0.1016)
			)
			(stroke
				(width 0)
				(type default)
			)
			(fill no)
			(layer "F.CrtYd")
		)
		(fp_line
			(start 0.3048 -0.1016)
			(end -0.3048 -0.1016)
			(stroke
				(width 0.1)
				(type default)
			)
			(layer "F.Fab")
		)
		(fp_line
			(start -0.3048 -0.1016)
			(end -0.3048 0.9906)
			(stroke
				(width 0.1)
				(type default)
			)
			(layer "F.Fab")
		)
		(fp_line
			(start 0.3048 0.9906)
			(end 0.3048 -0.1016)
			(stroke
				(width 0.1)
				(type default)
			)
			(layer "F.Fab")
		)
		(fp_line
			(start -0.3048 0.9906)
			(end 0.3048 0.9906)
			(stroke
				(width 0.1)
				(type default)
			)
			(layer "F.Fab")
		)
		(pad "1" smd rect
			(at 0 0 90)
			(size 0.508 0.508)
			(layers "F.Cu" "F.Mask" "F.Paste")
			(net "VR_FB_PVPP_GHJ")
		)
		(pad "2" smd rect
			(at 0 0.889 90)
			(size 0.508 0.508)
			(layers "F.Cu" "F.Mask" "F.Paste")
			(net "VR_COMP_PVPP_GHJ_3")
		)
		(zone
			(layer "F.Cu")
			(hatch none 0.5)
			(connect_pads
				(clearance 0)
			)
			(min_thickness 0.25)
			(keepout
				(tracks allowed)
				(vias not_allowed)
				(pads allowed)
				(copperpour not_allowed)
				(footprints allowed)
			)
			(placement
				(enabled no)
				(sheetname "")
			)
			(fill
				(thermal_gap 0.5)
				(thermal_bridge_width 0.5)
				(island_removal_mode 0)
			)
			(polygon
				(pts
					(xy 176.3395 -8.509) (xy 176.3395 -9.017) (xy 176.7205 -9.017) (xy 176.7205 -8.509)
				)
			)
		)
		(zone
			(layer "F.Cu")
			(hatch none 0.5)
			(connect_pads
				(clearance 0)
			)
			(min_thickness 0.25)
			(keepout
				(tracks not_allowed)
				(vias allowed)
				(pads allowed)
				(copperpour not_allowed)
				(footprints allowed)
			)
			(placement
				(enabled no)
				(sheetname "")
			)
			(fill
				(thermal_gap 0.5)
				(thermal_bridge_width 0.5)
				(island_removal_mode 0)
			)
			(polygon
				(pts
					(xy 176.7205 -8.509) (xy 176.7205 -9.017) (xy 176.3395 -9.017) (xy 176.3395 -8.509)
				)
			)
		)
	)
	(footprint ""
		(layer "F.Cu")
		(at 176.8856 -106.74985)
		(property "Reference" "R4C12"
			(at 0 0 0)
			(layer "F.SilkS")
			(hide yes)
			(effects
				(font
					(size 1.27 1.27)
				)
			)
		)
		(property "Value" ""
			(at 0 0 0)
			(layer "F.Fab")
			(effects
				(font
					(size 1.27 1.27)
				)
			)
		)
		(duplicate_pad_numbers_are_jumpers no)
		(fp_poly
			(pts
				(xy -0.2794 -0.1016) (xy 0.2794 -0.1016) (xy 0.2794 0.9906) (xy -0.2794 0.9906)
			)
			(stroke
				(width 0)
				(type default)
			)
			(fill no)
			(layer "F.CrtYd")
		)
		(fp_line
			(start -0.2794 -0.1016)
			(end -0.2794 0.9906)
			(stroke
				(width 0.1)
				(type default)
			)
			(layer "F.Fab")
		)
		(fp_line
			(start -0.2794 0.9906)
			(end 0.2794 0.9906)
			(stroke
				(width 0.1)
				(type default)
			)
			(layer "F.Fab")
		)
		(fp_line
			(start 0.2794 -0.1016)
			(end -0.2794 -0.1016)
			(stroke
				(width 0.1)
				(type default)
			)
			(layer "F.Fab")
		)
		(fp_line
			(start 0.2794 0.9906)
			(end 0.2794 -0.1016)
			(stroke
				(width 0.1)
				(type default)
			)
			(layer "F.Fab")
		)
		(pad "1" smd rect
			(at 0 0)
			(size 0.508 0.508)
			(layers "F.Cu" "F.Mask" "F.Paste")
			(net "VR_PVCCIOMCP_CPU1_XADDR1")
		)
		(pad "2" smd rect
			(at 0 0.889)
			(size 0.508 0.508)
			(layers "F.Cu" "F.Mask" "F.Paste")
			(net "GND")
		)
		(zone
			(layer "F.Cu")
			(hatch none 0.5)
			(connect_pads
				(clearance 0)
			)
			(min_thickness 0.25)
			(keepout
				(tracks allowed)
				(vias not_allowed)
				(pads allowed)
				(copperpour not_allowed)
				(footprints allowed)
			)
			(placement
				(enabled no)
				(sheetname "")
			)
			(fill
				(thermal_gap 0.5)
				(thermal_bridge_width 0.5)
				(island_removal_mode 0)
			)
			(polygon
				(pts
					(xy 176.6316 -106.49585) (xy 177.1396 -106.49585) (xy 177.1396 -106.11485) (xy 176.6316 -106.11485)
				)
			)
		)
		(zone
			(layer "F.Cu")
			(hatch none 0.5)
			(connect_pads
				(clearance 0)
			)
			(min_thickness 0.25)
			(keepout
				(tracks not_allowed)
				(vias allowed)
				(pads allowed)
				(copperpour not_allowed)
				(footprints allowed)
			)
			(placement
				(enabled no)
				(sheetname "")
			)
			(fill
				(thermal_gap 0.5)
				(thermal_bridge_width 0.5)
				(island_removal_mode 0)
			)
			(polygon
				(pts
					(xy 176.6316 -106.11485) (xy 177.1396 -106.11485) (xy 177.1396 -106.49585) (xy 176.6316 -106.49585)
				)
			)
		)
	)
	(footprint ""
		(layer "F.Cu")
		(at 25.7048 -50.419)
		(property "Reference" "C1E18"
			(at 4.16687 3.302 90)
			(unlocked yes)
			(layer "F.SilkS")
			(effects
				(font
					(size 0.7874 0.5842)
					(thickness 0.1524)
				)
				(justify left)
			)
		)
		(property "Value" ""
			(at 0 0 0)
			(layer "F.Fab")
			(effects
				(font
					(size 1.27 1.27)
				)
			)
		)
		(duplicate_pad_numbers_are_jumpers no)
		(fp_line
			(start -3.400044 0.028956)
			(end -3.400044 6.067044)
			(stroke
				(width 0.1524)
				(type default)
			)
			(layer "F.SilkS")
		)
		(fp_line
			(start -3.400044 6.067044)
			(end -0.9017 6.067044)
			(stroke
				(width 0.1524)
				(type default)
			)
			(layer "F.SilkS")
		)
		(fp_line
			(start -2.638044 -0.733044)
			(end -3.400044 0.028956)
			(stroke
				(width 0.1524)
				(type default)
			)
			(layer "F.SilkS")
		)
		(fp_line
			(start -0.9017 -1.714246)
			(end -0.9017 1.587754)
			(stroke
				(width 0.1524)
				(type default)
			)
			(layer "F.SilkS")
		)
		(fp_line
			(start -0.9017 -0.733044)
			(end -2.638044 -0.733044)
			(stroke
				(width 0.1524)
				(type default)
			)
			(layer "F.SilkS")
		)
		(fp_line
			(start -0.9017 1.587754)
			(end -0.7239 1.587754)
			(stroke
				(width 0.1524)
				(type default)
			)
			(layer "F.SilkS")
		)
		(fp_line
			(start -0.7239 -1.714246)
			(end -0.9017 -1.714246)
			(stroke
				(width 0.1524)
				(type default)
			)
			(layer "F.SilkS")
		)
		(fp_line
			(start 0.7239 1.587754)
			(end 0.9017 1.587754)
			(stroke
				(width 0.1524)
				(type default)
			)
			(layer "F.SilkS")
		)
		(fp_line
			(start 0.9017 -1.714246)
			(end 0.7239 -1.714246)
			(stroke
				(width 0.1524)
				(type default)
			)
			(layer "F.SilkS")
		)
		(fp_line
			(start 0.9017 1.587754)
			(end 0.9017 -1.714246)
			(stroke
				(width 0.1524)
				(type default)
			)
			(layer "F.SilkS")
		)
		(fp_line
			(start 0.9017 6.067044)
			(end 3.400044 6.067044)
			(stroke
				(width 0.1524)
				(type default)
			)
			(layer "F.SilkS")
		)
		(fp_line
			(start 2.638044 -0.733044)
			(end 0.9017 -0.733044)
			(stroke
				(width 0.1524)
				(type default)
			)
			(layer "F.SilkS")
		)
		(fp_line
			(start 3.400044 0.028956)
			(end 2.638044 -0.733044)
			(stroke
				(width 0.1524)
				(type default)
			)
			(layer "F.SilkS")
		)
		(fp_line
			(start 3.400044 6.067044)
			(end 3.400044 0.028956)
			(stroke
				(width 0.1524)
				(type default)
			)
			(layer "F.SilkS")
		)
		(fp_poly
			(pts
				(xy -3.400044 6.067044) (xy 3.400044 6.067044) (xy 3.400044 0.028956) (xy 2.638044 -0.733044) (xy -2.638044 -0.733044)
				(xy -3.400044 0.028956)
			)
			(stroke
				(width 0)
				(type default)
			)
			(fill no)
			(layer "F.CrtYd")
		)
		(fp_line
			(start -3.400044 0.028956)
			(end -3.400044 6.067044)
			(stroke
				(width 0.1)
				(type default)
			)
			(layer "F.Fab")
		)
		(fp_line
			(start -3.400044 6.067044)
			(end 3.400044 6.067044)
			(stroke
				(width 0.1)
				(type default)
			)
			(layer "F.Fab")
		)
		(fp_line
			(start -2.638044 -0.733044)
			(end -3.400044 0.028956)
			(stroke
				(width 0.1)
				(type default)
			)
			(layer "F.Fab")
		)
		(fp_line
			(start 2.638044 -0.733044)
			(end -2.638044 -0.733044)
			(stroke
				(width 0.1)
				(type default)
			)
			(layer "F.Fab")
		)
		(fp_line
			(start 3.400044 0.028956)
			(end 2.638044 -0.733044)
			(stroke
				(width 0.1)
				(type default)
			)
			(layer "F.Fab")
		)
		(fp_line
			(start 3.400044 6.067044)
			(end 3.400044 0.028956)
			(stroke
				(width 0.1)
				(type default)
			)
			(layer "F.Fab")
		)
		(fp_circle
			(center 0 2.667)
			(end 3.400044 2.667)
			(stroke
				(width 0.1)
				(type default)
			)
			(fill no)
			(layer "F.Fab")
		)
		(pad "1" smd rect
			(at 0 0)
			(size 0.7874 3.429)
			(layers "F.Cu" "F.Mask" "F.Paste")
			(net "VR_FET_SW_P12V_STBY_PVCCIN_CPU1")
		)
		(pad "2" smd rect
			(at 0 5.334)
			(size 0.7874 3.429)
			(layers "F.Cu" "F.Mask" "F.Paste")
			(net "GND")
		)
	)
	(footprint ""
		(layer "F.Cu")
		(at 258.1656 -12.9032 -90)
		(property "Reference" "C5G10"
			(at 0 0 270)
			(layer "F.SilkS")
			(hide yes)
			(effects
				(font
					(size 1.27 1.27)
				)
			)
		)
		(property "Value" ""
			(at 0 0 270)
			(layer "F.Fab")
			(effects
				(font
					(size 1.27 1.27)
				)
			)
		)
		(duplicate_pad_numbers_are_jumpers no)
		(fp_rect
			(start -0.500126 1.598422)
			(end 0.500126 -0.201422)
			(stroke
				(width 0)
				(type default)
			)
			(fill no)
			(layer "F.CrtYd")
		)
		(fp_line
			(start -0.500126 1.598422)
			(end -0.500126 -0.201422)
			(stroke
				(width 0.1)
				(type default)
			)
			(layer "F.Fab")
		)
		(fp_line
			(start 0.500126 1.598422)
			(end -0.500126 1.598422)
			(stroke
				(width 0.1)
				(type default)
			)
			(layer "F.Fab")
		)
		(fp_line
			(start -0.500126 -0.201422)
			(end 0.500126 -0.201422)
			(stroke
				(width 0.1)
				(type default)
			)
			(layer "F.Fab")
		)
		(fp_line
			(start 0.500126 -0.201422)
			(end 0.500126 1.598422)
			(stroke
				(width 0.1)
				(type default)
			)
			(layer "F.Fab")
		)
		(pad "1" smd rect
			(at 0 0 180)
			(size 0.889 0.9906)
			(layers "F.Cu" "F.Mask" "F.Paste")
			(net "PVDDQ_ABC")
		)
		(pad "2" smd rect
			(at 0 1.397 180)
			(size 0.889 0.9906)
			(layers "F.Cu" "F.Mask" "F.Paste")
			(net "GND")
		)
		(zone
			(layer "F.Cu")
			(hatch none 0.5)
			(connect_pads
				(clearance 0)
			)
			(min_thickness 0.25)
			(keepout
				(tracks not_allowed)
				(vias allowed)
				(pads allowed)
				(copperpour not_allowed)
				(footprints allowed)
			)
			(placement
				(enabled no)
				(sheetname "")
			)
			(fill
				(thermal_gap 0.5)
				(thermal_bridge_width 0.5)
				(island_removal_mode 0)
			)
			(polygon
				(pts
					(xy 257.2131 -13.3985) (xy 257.2131 -12.4079) (xy 257.7211 -12.4079) (xy 257.7211 -13.3985)
				)
			)
		)
		(zone
			(layer "F.Cu")
			(hatch none 0.5)
			(connect_pads
				(clearance 0)
			)
			(min_thickness 0.25)
			(keepout
				(tracks allowed)
				(vias not_allowed)
				(pads allowed)
				(copperpour not_allowed)
				(footprints allowed)
			)
			(placement
				(enabled no)
				(sheetname "")
			)
			(fill
				(thermal_gap 0.5)
				(thermal_bridge_width 0.5)
				(island_removal_mode 0)
			)
			(polygon
				(pts
					(xy 257.2131 -13.3985) (xy 257.2131 -12.4079) (xy 257.7211 -12.4079) (xy 257.7211 -13.3985)
				)
			)
		)
	)
)
